(kicad_pcb
	(version 20260206)
	(generator "pcbnew")
	(generator_version "10.0")
	(general
		(thickness 1.6)
		(legacy_teardrops no)
	)
	(paper "A4")
	(title_block
		(title "04192023_DAF0TMB3IC0_F0TG_MB_C_brd_V02_OCP.brd")
		(comment 1 "Grand Teton / footprints 99-105 of 8354")
	)
	(layers
		(0 "F.Cu" signal "TOP")
		(4 "In1.Cu" signal "GND")
		(6 "In2.Cu" signal "IN1")
		(8 "In3.Cu" signal "GND1")
		(10 "In4.Cu" signal "IN2")
		(12 "In5.Cu" signal "GND2")
		(14 "In6.Cu" signal "IN3")
		(16 "In7.Cu" signal "GND3")
		(18 "In8.Cu" signal "VCC")
		(20 "In9.Cu" signal "VCC1")
		(22 "In10.Cu" signal "GND4")
		(24 "In11.Cu" signal "IN4")
		(26 "In12.Cu" signal "GND5")
		(28 "In13.Cu" signal "IN5")
		(30 "In14.Cu" signal "GND6")
		(32 "In15.Cu" signal "IN6")
		(34 "In16.Cu" signal "GND7")
		(2 "B.Cu" signal "BOTTOM")
		(9 "F.Adhes" user "F.Adhesive")
		(11 "B.Adhes" user "B.Adhesive")
		(13 "F.Paste" user "Package Geometry/Pastemask Top")
		(15 "B.Paste" user "Package Geometry/Pastemask Bottom")
		(5 "F.SilkS" user "Ref Des/Silkscreen Top")
		(7 "B.SilkS" user "Ref Des/Silkscreen Bottom")
		(1 "F.Mask" user "Board Geometry/Soldermask Top")
		(3 "B.Mask" user "Board Geometry/Soldermask Bottom")
		(17 "Dwgs.User" user "User.Drawings")
		(19 "Cmts.User" user "User.Comments")
		(21 "Eco1.User" user "User.Eco1")
		(23 "Eco2.User" user "User.Eco2")
		(25 "Edge.Cuts" user "Board Geometry/Outline")
		(27 "Margin" user)
		(31 "F.CrtYd" user "Package Geometry/Place Bound Top")
		(29 "B.CrtYd" user "Package Geometry/Place Bound Bottom")
		(35 "F.Fab" user "Ref Des/Assembly Top")
		(33 "B.Fab" user "Ref Des/Assembly Bottom")
	)
	(footprint ""
		(layer "F.Cu")
		(at 271.085056 -115.22837)
		(property "Reference" "R3721"
			(at 0 0 0)
			(layer "F.SilkS")
			(hide yes)
			(effects
				(font
					(size 1.27 1.27)
				)
			)
		)
		(property "Value" ""
			(at 0 0 0)
			(layer "F.Fab")
			(effects
				(font
					(size 1.27 1.27)
				)
			)
		)
		(duplicate_pad_numbers_are_jumpers no)
		(fp_line
			(start -0.7874 -0.4064)
			(end 0.7874 -0.4064)
			(stroke
				(width 0.1524)
				(type default)
			)
			(layer "F.SilkS")
		)
		(fp_line
			(start -0.7874 0.4064)
			(end -0.7874 -0.4064)
			(stroke
				(width 0.1524)
				(type default)
			)
			(layer "F.SilkS")
		)
		(fp_line
			(start 0.7874 -0.4064)
			(end 0.7874 0.4064)
			(stroke
				(width 0.1524)
				(type default)
			)
			(layer "F.SilkS")
		)
		(fp_line
			(start 0.7874 0.4064)
			(end -0.7874 0.4064)
			(stroke
				(width 0.1524)
				(type default)
			)
			(layer "F.SilkS")
		)
		(fp_line
			(start -0.67945 -0.305054)
			(end -0.12065 -0.305054)
			(stroke
				(width 0.1)
				(type default)
			)
			(layer "F.Fab")
		)
		(fp_line
			(start -0.67945 0.3048)
			(end -0.67945 -0.305054)
			(stroke
				(width 0.1)
				(type default)
			)
			(layer "F.Fab")
		)
		(fp_line
			(start -0.12065 -0.305054)
			(end -0.12065 -0.2794)
			(stroke
				(width 0.1)
				(type default)
			)
			(layer "F.Fab")
		)
		(fp_line
			(start -0.12065 -0.2794)
			(end 0.12065 -0.2794)
			(stroke
				(width 0.1)
				(type default)
			)
			(layer "F.Fab")
		)
		(fp_line
			(start -0.12065 0.2794)
			(end -0.12065 0.3048)
			(stroke
				(width 0.1)
				(type default)
			)
			(layer "F.Fab")
		)
		(fp_line
			(start -0.12065 0.3048)
			(end -0.67945 0.3048)
			(stroke
				(width 0.1)
				(type default)
			)
			(layer "F.Fab")
		)
		(fp_line
			(start 0.120396 0.2794)
			(end -0.12065 0.2794)
			(stroke
				(width 0.1)
				(type default)
			)
			(layer "F.Fab")
		)
		(fp_line
			(start 0.120396 0.3048)
			(end 0.120396 0.2794)
			(stroke
				(width 0.1)
				(type default)
			)
			(layer "F.Fab")
		)
		(fp_line
			(start 0.12065 -0.3048)
			(end 0.67945 -0.3048)
			(stroke
				(width 0.1)
				(type default)
			)
			(layer "F.Fab")
		)
		(fp_line
			(start 0.12065 -0.2794)
			(end 0.12065 -0.3048)
			(stroke
				(width 0.1)
				(type default)
			)
			(layer "F.Fab")
		)
		(fp_line
			(start 0.67945 -0.3048)
			(end 0.67945 0.3048)
			(stroke
				(width 0.1)
				(type default)
			)
			(layer "F.Fab")
		)
		(fp_line
			(start 0.67945 0.3048)
			(end 0.120396 0.3048)
			(stroke
				(width 0.1)
				(type default)
			)
			(layer "F.Fab")
		)
		(pad "1" smd circle
			(at -0.40005 0)
			(size 0 0)
			(layers "F.Cu" "F.Mask" "F.Paste")
			(net "SMB_LM75_3_3V3AUX_SCL_R")
		)
		(pad "2" smd circle
			(at 0.40005 0)
			(size 0 0)
			(layers "F.Cu" "F.Mask" "F.Paste")
			(net "SMB_LM75_3_3V3AUX_SCL")
		)
	)
	(footprint ""
		(layer "F.Cu")
		(at 296.22877 -351.100644)
		(property "Reference" "PC148_1"
			(at 0 0 0)
			(layer "F.SilkS")
			(hide yes)
			(effects
				(font
					(size 1.27 1.27)
				)
			)
		)
		(property "Value" ""
			(at 0 0 0)
			(layer "F.Fab")
			(effects
				(font
					(size 1.27 1.27)
				)
			)
		)
		(duplicate_pad_numbers_are_jumpers no)
		(fp_line
			(start -0.7874 -0.4064)
			(end 0.7874 -0.4064)
			(stroke
				(width 0.1524)
				(type default)
			)
			(layer "F.SilkS")
		)
		(fp_line
			(start -0.7874 0.4064)
			(end -0.7874 -0.4064)
			(stroke
				(width 0.1524)
				(type default)
			)
			(layer "F.SilkS")
		)
		(fp_line
			(start 0.7874 -0.4064)
			(end 0.7874 0.4064)
			(stroke
				(width 0.1524)
				(type default)
			)
			(layer "F.SilkS")
		)
		(fp_line
			(start 0.7874 0.4064)
			(end -0.7874 0.4064)
			(stroke
				(width 0.1524)
				(type default)
			)
			(layer "F.SilkS")
		)
		(fp_line
			(start -0.67945 -0.305054)
			(end -0.12065 -0.305054)
			(stroke
				(width 0.1)
				(type default)
			)
			(layer "F.Fab")
		)
		(fp_line
			(start -0.67945 0.3048)
			(end -0.67945 -0.305054)
			(stroke
				(width 0.1)
				(type default)
			)
			(layer "F.Fab")
		)
		(fp_line
			(start -0.12065 -0.305054)
			(end -0.12065 -0.2794)
			(stroke
				(width 0.1)
				(type default)
			)
			(layer "F.Fab")
		)
		(fp_line
			(start -0.12065 -0.2794)
			(end 0.12065 -0.2794)
			(stroke
				(width 0.1)
				(type default)
			)
			(layer "F.Fab")
		)
		(fp_line
			(start -0.12065 0.2794)
			(end -0.12065 0.3048)
			(stroke
				(width 0.1)
				(type default)
			)
			(layer "F.Fab")
		)
		(fp_line
			(start -0.12065 0.3048)
			(end -0.67945 0.3048)
			(stroke
				(width 0.1)
				(type default)
			)
			(layer "F.Fab")
		)
		(fp_line
			(start 0.120396 0.2794)
			(end -0.12065 0.2794)
			(stroke
				(width 0.1)
				(type default)
			)
			(layer "F.Fab")
		)
		(fp_line
			(start 0.120396 0.3048)
			(end 0.120396 0.2794)
			(stroke
				(width 0.1)
				(type default)
			)
			(layer "F.Fab")
		)
		(fp_line
			(start 0.12065 -0.3048)
			(end 0.67945 -0.3048)
			(stroke
				(width 0.1)
				(type default)
			)
			(layer "F.Fab")
		)
		(fp_line
			(start 0.12065 -0.2794)
			(end 0.12065 -0.3048)
			(stroke
				(width 0.1)
				(type default)
			)
			(layer "F.Fab")
		)
		(fp_line
			(start 0.67945 -0.3048)
			(end 0.67945 0.3048)
			(stroke
				(width 0.1)
				(type default)
			)
			(layer "F.Fab")
		)
		(fp_line
			(start 0.67945 0.3048)
			(end 0.120396 0.3048)
			(stroke
				(width 0.1)
				(type default)
			)
			(layer "F.Fab")
		)
		(pad "1" smd circle
			(at -0.40005 0)
			(size 0 0)
			(layers "F.Cu" "F.Mask" "F.Paste")
			(net "SW_P12V_AUX_PVDDIO_P0_FLT")
		)
		(pad "2" smd circle
			(at 0.40005 0)
			(size 0 0)
			(layers "F.Cu" "F.Mask" "F.Paste")
			(net "GND")
		)
	)
	(footprint ""
		(layer "F.Cu")
		(at 22.147784 -393.539726 180)
		(property "Reference" "PC6646"
			(at 0 0 180)
			(layer "F.SilkS")
			(hide yes)
			(effects
				(font
					(size 1.27 1.27)
				)
			)
		)
		(property "Value" ""
			(at 0 0 180)
			(layer "F.Fab")
			(effects
				(font
					(size 1.27 1.27)
				)
			)
		)
		(duplicate_pad_numbers_are_jumpers no)
		(fp_line
			(start 0.7874 0.4064)
			(end -0.7874 0.4064)
			(stroke
				(width 0.1524)
				(type default)
			)
			(layer "F.SilkS")
		)
		(fp_line
			(start 0.7874 -0.4064)
			(end 0.7874 0.4064)
			(stroke
				(width 0.1524)
				(type default)
			)
			(layer "F.SilkS")
		)
		(fp_line
			(start -0.7874 0.4064)
			(end -0.7874 -0.4064)
			(stroke
				(width 0.1524)
				(type default)
			)
			(layer "F.SilkS")
		)
		(fp_line
			(start -0.7874 -0.4064)
			(end 0.7874 -0.4064)
			(stroke
				(width 0.1524)
				(type default)
			)
			(layer "F.SilkS")
		)
		(fp_line
			(start 0.67945 0.3048)
			(end 0.120396 0.3048)
			(stroke
				(width 0.1)
				(type default)
			)
			(layer "F.Fab")
		)
		(fp_line
			(start 0.67945 -0.3048)
			(end 0.67945 0.3048)
			(stroke
				(width 0.1)
				(type default)
			)
			(layer "F.Fab")
		)
		(fp_line
			(start 0.12065 -0.2794)
			(end 0.12065 -0.3048)
			(stroke
				(width 0.1)
				(type default)
			)
			(layer "F.Fab")
		)
		(fp_line
			(start 0.12065 -0.3048)
			(end 0.67945 -0.3048)
			(stroke
				(width 0.1)
				(type default)
			)
			(layer "F.Fab")
		)
		(fp_line
			(start 0.120396 0.3048)
			(end 0.120396 0.2794)
			(stroke
				(width 0.1)
				(type default)
			)
			(layer "F.Fab")
		)
		(fp_line
			(start 0.120396 0.2794)
			(end -0.12065 0.2794)
			(stroke
				(width 0.1)
				(type default)
			)
			(layer "F.Fab")
		)
		(fp_line
			(start -0.12065 0.3048)
			(end -0.67945 0.3048)
			(stroke
				(width 0.1)
				(type default)
			)
			(layer "F.Fab")
		)
		(fp_line
			(start -0.12065 0.2794)
			(end -0.12065 0.3048)
			(stroke
				(width 0.1)
				(type default)
			)
			(layer "F.Fab")
		)
		(fp_line
			(start -0.12065 -0.2794)
			(end 0.12065 -0.2794)
			(stroke
				(width 0.1)
				(type default)
			)
			(layer "F.Fab")
		)
		(fp_line
			(start -0.12065 -0.305054)
			(end -0.12065 -0.2794)
			(stroke
				(width 0.1)
				(type default)
			)
			(layer "F.Fab")
		)
		(fp_line
			(start -0.67945 0.3048)
			(end -0.67945 -0.305054)
			(stroke
				(width 0.1)
				(type default)
			)
			(layer "F.Fab")
		)
		(fp_line
			(start -0.67945 -0.305054)
			(end -0.12065 -0.305054)
			(stroke
				(width 0.1)
				(type default)
			)
			(layer "F.Fab")
		)
		(pad "1" smd circle
			(at -0.40005 0 180)
			(size 0 0)
			(layers "F.Cu" "F.Mask" "F.Paste")
			(net "PV09_RETIMER_CPU1_VCCS")
		)
		(pad "2" smd circle
			(at 0.40005 0 180)
			(size 0 0)
			(layers "F.Cu" "F.Mask" "F.Paste")
			(net "GND")
		)
	)
	(footprint ""
		(layer "F.Cu")
		(at 439.512456 -43.929554 90)
		(property "Reference" "PC1649"
			(at 0 0 90)
			(layer "F.SilkS")
			(hide yes)
			(effects
				(font
					(size 1.27 1.27)
				)
			)
		)
		(property "Value" ""
			(at 0 0 90)
			(layer "F.Fab")
			(effects
				(font
					(size 1.27 1.27)
				)
			)
		)
		(duplicate_pad_numbers_are_jumpers no)
		(fp_line
			(start 0.7874 -0.4064)
			(end 0.7874 0.4064)
			(stroke
				(width 0.1524)
				(type default)
			)
			(layer "F.SilkS")
		)
		(fp_line
			(start -0.7874 -0.4064)
			(end 0.7874 -0.4064)
			(stroke
				(width 0.1524)
				(type default)
			)
			(layer "F.SilkS")
		)
		(fp_line
			(start 0.7874 0.4064)
			(end -0.7874 0.4064)
			(stroke
				(width 0.1524)
				(type default)
			)
			(layer "F.SilkS")
		)
		(fp_line
			(start -0.7874 0.4064)
			(end -0.7874 -0.4064)
			(stroke
				(width 0.1524)
				(type default)
			)
			(layer "F.SilkS")
		)
		(fp_line
			(start -0.12065 -0.305054)
			(end -0.12065 -0.2794)
			(stroke
				(width 0.1)
				(type default)
			)
			(layer "F.Fab")
		)
		(fp_line
			(start -0.67945 -0.305054)
			(end -0.12065 -0.305054)
			(stroke
				(width 0.1)
				(type default)
			)
			(layer "F.Fab")
		)
		(fp_line
			(start 0.67945 -0.3048)
			(end 0.67945 0.3048)
			(stroke
				(width 0.1)
				(type default)
			)
			(layer "F.Fab")
		)
		(fp_line
			(start 0.12065 -0.3048)
			(end 0.67945 -0.3048)
			(stroke
				(width 0.1)
				(type default)
			)
			(layer "F.Fab")
		)
		(fp_line
			(start 0.12065 -0.2794)
			(end 0.12065 -0.3048)
			(stroke
				(width 0.1)
				(type default)
			)
			(layer "F.Fab")
		)
		(fp_line
			(start -0.12065 -0.2794)
			(end 0.12065 -0.2794)
			(stroke
				(width 0.1)
				(type default)
			)
			(layer "F.Fab")
		)
		(fp_line
			(start 0.120396 0.2794)
			(end -0.12065 0.2794)
			(stroke
				(width 0.1)
				(type default)
			)
			(layer "F.Fab")
		)
		(fp_line
			(start -0.12065 0.2794)
			(end -0.12065 0.3048)
			(stroke
				(width 0.1)
				(type default)
			)
			(layer "F.Fab")
		)
		(fp_line
			(start 0.67945 0.3048)
			(end 0.120396 0.3048)
			(stroke
				(width 0.1)
				(type default)
			)
			(layer "F.Fab")
		)
		(fp_line
			(start 0.120396 0.3048)
			(end 0.120396 0.2794)
			(stroke
				(width 0.1)
				(type default)
			)
			(layer "F.Fab")
		)
		(fp_line
			(start -0.12065 0.3048)
			(end -0.67945 0.3048)
			(stroke
				(width 0.1)
				(type default)
			)
			(layer "F.Fab")
		)
		(fp_line
			(start -0.67945 0.3048)
			(end -0.67945 -0.305054)
			(stroke
				(width 0.1)
				(type default)
			)
			(layer "F.Fab")
		)
		(pad "1" smd circle
			(at -0.40005 0 90)
			(size 0 0)
			(layers "F.Cu" "F.Mask" "F.Paste")
			(net "P12V_AUX")
		)
		(pad "2" smd circle
			(at 0.40005 0 90)
			(size 0 0)
			(layers "F.Cu" "F.Mask" "F.Paste")
			(net "GND")
		)
	)
	(footprint ""
		(layer "F.Cu")
		(at 435.43982 -399.029936)
		(property "Reference" "H10"
			(at -3.815588 -3.882644 0)
			(unlocked yes)
			(layer "F.SilkS")
			(effects
				(font
					(size 0.7874 0.5842)
					(thickness 0.1524)
				)
				(justify left)
			)
		)
		(property "Value" ""
			(at 0 0 0)
			(layer "F.Fab")
			(effects
				(font
					(size 1.27 1.27)
				)
			)
		)
		(duplicate_pad_numbers_are_jumpers no)
		(pad "1" thru_hole circle
			(at 0 0)
			(size 6.1976 6.1976)
			(drill 3.7338)
			(layers "*.Cu" "*.Mask")
			(remove_unused_layers no)
			(net "GND")
			(clearance -0.9779)
			(padstack
				(mode front_inner_back)
				(layer "Inner"
					(shape circle)
					(size 5.5372 5.5372)
					(clearance -0.6477)
				)
				(layer "B.Cu"
					(shape circle)
					(size 6.1976 6.1976)
					(clearance -0.9779)
				)
			)
		)
	)
	(footprint ""
		(layer "F.Cu")
		(at 279.513792 -120.74017 180)
		(property "Reference" "R6200"
			(at 0 0 180)
			(layer "F.SilkS")
			(hide yes)
			(effects
				(font
					(size 1.27 1.27)
				)
			)
		)
		(property "Value" ""
			(at 0 0 180)
			(layer "F.Fab")
			(effects
				(font
					(size 1.27 1.27)
				)
			)
		)
		(duplicate_pad_numbers_are_jumpers no)
		(fp_line
			(start 0.7874 0.4064)
			(end -0.7874 0.4064)
			(stroke
				(width 0.1524)
				(type default)
			)
			(layer "F.SilkS")
		)
		(fp_line
			(start 0.7874 -0.4064)
			(end 0.7874 0.4064)
			(stroke
				(width 0.1524)
				(type default)
			)
			(layer "F.SilkS")
		)
		(fp_line
			(start -0.7874 0.4064)
			(end -0.7874 -0.4064)
			(stroke
				(width 0.1524)
				(type default)
			)
			(layer "F.SilkS")
		)
		(fp_line
			(start -0.7874 -0.4064)
			(end 0.7874 -0.4064)
			(stroke
				(width 0.1524)
				(type default)
			)
			(layer "F.SilkS")
		)
		(fp_line
			(start 0.67945 0.3048)
			(end 0.120396 0.3048)
			(stroke
				(width 0.1)
				(type default)
			)
			(layer "F.Fab")
		)
		(fp_line
			(start 0.67945 -0.3048)
			(end 0.67945 0.3048)
			(stroke
				(width 0.1)
				(type default)
			)
			(layer "F.Fab")
		)
		(fp_line
			(start 0.12065 -0.2794)
			(end 0.12065 -0.3048)
			(stroke
				(width 0.1)
				(type default)
			)
			(layer "F.Fab")
		)
		(fp_line
			(start 0.12065 -0.3048)
			(end 0.67945 -0.3048)
			(stroke
				(width 0.1)
				(type default)
			)
			(layer "F.Fab")
		)
		(fp_line
			(start 0.120396 0.3048)
			(end 0.120396 0.2794)
			(stroke
				(width 0.1)
				(type default)
			)
			(layer "F.Fab")
		)
		(fp_line
			(start 0.120396 0.2794)
			(end -0.12065 0.2794)
			(stroke
				(width 0.1)
				(type default)
			)
			(layer "F.Fab")
		)
		(fp_line
			(start -0.12065 0.3048)
			(end -0.67945 0.3048)
			(stroke
				(width 0.1)
				(type default)
			)
			(layer "F.Fab")
		)
		(fp_line
			(start -0.12065 0.2794)
			(end -0.12065 0.3048)
			(stroke
				(width 0.1)
				(type default)
			)
			(layer "F.Fab")
		)
		(fp_line
			(start -0.12065 -0.2794)
			(end 0.12065 -0.2794)
			(stroke
				(width 0.1)
				(type default)
			)
			(layer "F.Fab")
		)
		(fp_line
			(start -0.12065 -0.305054)
			(end -0.12065 -0.2794)
			(stroke
				(width 0.1)
				(type default)
			)
			(layer "F.Fab")
		)
		(fp_line
			(start -0.67945 0.3048)
			(end -0.67945 -0.305054)
			(stroke
				(width 0.1)
				(type default)
			)
			(layer "F.Fab")
		)
		(fp_line
			(start -0.67945 -0.305054)
			(end -0.12065 -0.305054)
			(stroke
				(width 0.1)
				(type default)
			)
			(layer "F.Fab")
		)
		(pad "1" smd circle
			(at -0.40005 0 180)
			(size 0 0)
			(layers "F.Cu" "F.Mask" "F.Paste")
			(net "SMB_USB_CPU0_HUB1_SDA_R")
		)
		(pad "2" smd circle
			(at 0.40005 0 180)
			(size 0 0)
			(layers "F.Cu" "F.Mask" "F.Paste")
			(net "SMB_USB_CPU0_HUB1_SDA")
		)
	)
	(footprint ""
		(layer "F.Cu")
		(at 438.257442 -428.918624 -90)
		(property "Reference" "R6860"
			(at 0 0 270)
			(layer "F.SilkS")
			(hide yes)
			(effects
				(font
					(size 1.27 1.27)
				)
			)
		)
		(property "Value" ""
			(at 0 0 270)
			(layer "F.Fab")
			(effects
				(font
					(size 1.27 1.27)
				)
			)
		)
		(duplicate_pad_numbers_are_jumpers no)
		(fp_line
			(start -0.7874 0.4064)
			(end -0.7874 -0.4064)
			(stroke
				(width 0.1524)
				(type default)
			)
			(layer "F.SilkS")
		)
		(fp_line
			(start 0.7874 0.4064)
			(end -0.7874 0.4064)
			(stroke
				(width 0.1524)
				(type default)
			)
			(layer "F.SilkS")
		)
		(fp_line
			(start -0.7874 -0.4064)
			(end 0.7874 -0.4064)
			(stroke
				(width 0.1524)
				(type default)
			)
			(layer "F.SilkS")
		)
		(fp_line
			(start 0.7874 -0.4064)
			(end 0.7874 0.4064)
			(stroke
				(width 0.1524)
				(type default)
			)
			(layer "F.SilkS")
		)
		(fp_line
			(start -0.67945 0.3048)
			(end -0.67945 -0.305054)
			(stroke
				(width 0.1)
				(type default)
			)
			(layer "F.Fab")
		)
		(fp_line
			(start -0.12065 0.3048)
			(end -0.67945 0.3048)
			(stroke
				(width 0.1)
				(type default)
			)
			(layer "F.Fab")
		)
		(fp_line
			(start 0.120396 0.3048)
			(end 0.120396 0.2794)
			(stroke
				(width 0.1)
				(type default)
			)
			(layer "F.Fab")
		)
		(fp_line
			(start 0.67945 0.3048)
			(end 0.120396 0.3048)
			(stroke
				(width 0.1)
				(type default)
			)
			(layer "F.Fab")
		)
		(fp_line
			(start -0.12065 0.2794)
			(end -0.12065 0.3048)
			(stroke
				(width 0.1)
				(type default)
			)
			(layer "F.Fab")
		)
		(fp_line
			(start 0.120396 0.2794)
			(end -0.12065 0.2794)
			(stroke
				(width 0.1)
				(type default)
			)
			(layer "F.Fab")
		)
		(fp_line
			(start -0.12065 -0.2794)
			(end 0.12065 -0.2794)
			(stroke
				(width 0.1)
				(type default)
			)
			(layer "F.Fab")
		)
		(fp_line
			(start 0.12065 -0.2794)
			(end 0.12065 -0.3048)
			(stroke
				(width 0.1)
				(type default)
			)
			(layer "F.Fab")
		)
		(fp_line
			(start 0.12065 -0.3048)
			(end 0.67945 -0.3048)
			(stroke
				(width 0.1)
				(type default)
			)
			(layer "F.Fab")
		)
		(fp_line
			(start 0.67945 -0.3048)
			(end 0.67945 0.3048)
			(stroke
				(width 0.1)
				(type default)
			)
			(layer "F.Fab")
		)
		(fp_line
			(start -0.67945 -0.305054)
			(end -0.12065 -0.305054)
			(stroke
				(width 0.1)
				(type default)
			)
			(layer "F.Fab")
		)
		(fp_line
			(start -0.12065 -0.305054)
			(end -0.12065 -0.2794)
			(stroke
				(width 0.1)
				(type default)
			)
			(layer "F.Fab")
		)
		(pad "1" smd circle
			(at -0.40005 0 270)
			(size 0 0)
			(layers "F.Cu" "F.Mask" "F.Paste")
			(net "P1V8_AUX")
		)
		(pad "2" smd circle
			(at 0.40005 0 270)
			(size 0 0)
			(layers "F.Cu" "F.Mask" "F.Paste")
			(net "PWRGD_P0V9_RETIMER_CPU0_R")
		)
	)
)
